(kicad_pcb
	(version 20260206)
	(generator "pcbnew")
	(generator_version "10.0")
	(general
		(thickness 1.6)
		(legacy_teardrops no)
	)
	(paper "A4")
	(title_block
		(title "Wiwynn_Tioga_Pass_MB.brd")
		(comment 1 "Tioga Pass / footprints 4219-4225 of 4770")
	)
	(layers
		(0 "F.Cu" signal "TOP")
		(4 "In1.Cu" signal "L2GND")
		(6 "In2.Cu" signal "L3")
		(8 "In3.Cu" signal "L4GND")
		(10 "In4.Cu" signal "L5")
		(12 "In5.Cu" signal "L6GND")
		(14 "In6.Cu" signal "L7VCC")
		(16 "In7.Cu" signal "L8VCC")
		(18 "In8.Cu" signal "L9GND")
		(20 "In9.Cu" signal "L10")
		(22 "In10.Cu" signal "L11GND")
		(24 "In11.Cu" signal "L12")
		(26 "In12.Cu" signal "L13GND")
		(2 "B.Cu" signal "BOTTOM")
		(9 "F.Adhes" user "F.Adhesive")
		(11 "B.Adhes" user "B.Adhesive")
		(13 "F.Paste" user "Package Geometry/Pastemask Top")
		(15 "B.Paste" user "Package Geometry/Pastemask Bottom")
		(5 "F.SilkS" user "Ref Des/Silkscreen Top")
		(7 "B.SilkS" user "Ref Des/Silkscreen Bottom")
		(1 "F.Mask" user "Board Geometry/Soldermask Top")
		(3 "B.Mask" user "Board Geometry/Soldermask Bottom")
		(17 "Dwgs.User" user "User.Drawings")
		(19 "Cmts.User" user "User.Comments")
		(21 "Eco1.User" user "User.Eco1")
		(23 "Eco2.User" user "User.Eco2")
		(25 "Edge.Cuts" user "Board Geometry/Outline")
		(27 "Margin" user)
		(31 "F.CrtYd" user "Package Geometry/Place Bound Top")
		(29 "B.CrtYd" user "Package Geometry/Place Bound Bottom")
		(35 "F.Fab" user "Ref Des/Assembly Top")
		(33 "B.Fab" user "Ref Des/Assembly Bottom")
	)
	(footprint ""
		(layer "B.Cu")
		(at 376.344688 -69.895466 180)
		(property "Reference" "C2P6"
			(at 0 0 0)
			(layer "B.SilkS")
			(hide yes)
			(effects
				(font
					(size 1.27 1.27)
				)
				(justify mirror)
			)
		)
		(property "Value" ""
			(at 0 0 0)
			(layer "B.Fab")
			(effects
				(font
					(size 1.27 1.27)
				)
				(justify mirror)
			)
		)
		(duplicate_pad_numbers_are_jumpers no)
		(fp_rect
			(start 0.2794 0.9144)
			(end -0.2794 -0.1143)
			(stroke
				(width 0)
				(type default)
			)
			(fill no)
			(layer "B.CrtYd")
		)
		(fp_line
			(start 0.2794 0.9144)
			(end 0.2794 -0.1143)
			(stroke
				(width 0.1)
				(type default)
			)
			(layer "B.Fab")
		)
		(fp_line
			(start 0.2794 -0.1143)
			(end -0.2794 -0.1143)
			(stroke
				(width 0.1)
				(type default)
			)
			(layer "B.Fab")
		)
		(fp_line
			(start -0.2794 0.9144)
			(end 0.2794 0.9144)
			(stroke
				(width 0.1)
				(type default)
			)
			(layer "B.Fab")
		)
		(fp_line
			(start -0.2794 -0.1143)
			(end -0.2794 0.9144)
			(stroke
				(width 0.1)
				(type default)
			)
			(layer "B.Fab")
		)
		(pad "1" smd custom
			(at 0 0 90)
			(size 0.10414 0.10414)
			(layers "B.Cu" "B.Mask" "B.Paste")
			(net "P3V3_STBY")
			(options
				(clearance outline)
				(anchor circle)
			)
			(primitives
				(gr_poly
					(pts
						(xy -0.20828 -0.08636) (xy -0.20828 0.08636) (xy -0.08636 0.20828) (xy 0.086614 0.20828) (xy 0.20828 0.086614)
						(xy 0.20828 -0.08636) (xy 0.08636 -0.20828) (xy -0.08636 -0.20828)
					)
					(width 0)
					(fill yes)
				)
			)
		)
		(pad "2" smd custom
			(at 0 0.8001 90)
			(size 0.10414 0.10414)
			(layers "B.Cu" "B.Mask" "B.Paste")
			(net "GND")
			(options
				(clearance outline)
				(anchor circle)
			)
			(primitives
				(gr_poly
					(pts
						(xy -0.20828 -0.08636) (xy -0.20828 0.08636) (xy -0.08636 0.20828) (xy 0.086614 0.20828) (xy 0.20828 0.086614)
						(xy 0.20828 -0.08636) (xy 0.08636 -0.20828) (xy -0.08636 -0.20828)
					)
					(width 0)
					(fill yes)
				)
			)
		)
		(zone
			(layer "B.Cu")
			(hatch none 0.5)
			(connect_pads
				(clearance 0)
			)
			(min_thickness 0.25)
			(keepout
				(tracks not_allowed)
				(vias allowed)
				(pads allowed)
				(copperpour not_allowed)
				(footprints allowed)
			)
			(placement
				(enabled no)
				(sheetname "")
			)
			(fill
				(thermal_gap 0.5)
				(thermal_bridge_width 0.5)
				(island_removal_mode 0)
			)
			(polygon
				(pts
					(xy 376.257058 -70.105016) (xy 376.257058 -70.486016) (xy 376.432318 -70.486016) (xy 376.432572 -70.105016)
				)
			)
		)
		(zone
			(layer "B.Cu")
			(hatch none 0.5)
			(connect_pads
				(clearance 0)
			)
			(min_thickness 0.25)
			(keepout
				(tracks allowed)
				(vias not_allowed)
				(pads allowed)
				(copperpour not_allowed)
				(footprints allowed)
			)
			(placement
				(enabled no)
				(sheetname "")
			)
			(fill
				(thermal_gap 0.5)
				(thermal_bridge_width 0.5)
				(island_removal_mode 0)
			)
			(polygon
				(pts
					(xy 376.257058 -70.105016) (xy 376.257058 -70.486016) (xy 376.432318 -70.486016) (xy 376.432572 -70.105016)
				)
			)
		)
	)
	(footprint ""
		(layer "B.Cu")
		(at 80.81518 -125.64745 90)
		(property "Reference" "C8M10"
			(at -1.17602 3.79222 0)
			(unlocked yes)
			(layer "B.SilkS")
			(effects
				(font
					(size 0.7874 0.5842)
					(thickness 0.1524)
				)
				(justify mirror)
			)
		)
		(property "Value" ""
			(at 0 0 90)
			(layer "B.Fab")
			(effects
				(font
					(size 1.27 1.27)
				)
				(justify mirror)
			)
		)
		(duplicate_pad_numbers_are_jumpers no)
		(fp_rect
			(start 0.500126 1.598422)
			(end -0.500126 -0.201422)
			(stroke
				(width 0)
				(type default)
			)
			(fill no)
			(layer "B.CrtYd")
		)
		(fp_line
			(start 0.500126 -0.201422)
			(end -0.500126 -0.201422)
			(stroke
				(width 0.1)
				(type default)
			)
			(layer "B.Fab")
		)
		(fp_line
			(start -0.500126 -0.201422)
			(end -0.500126 1.598422)
			(stroke
				(width 0.1)
				(type default)
			)
			(layer "B.Fab")
		)
		(fp_line
			(start 0.500126 1.598422)
			(end 0.500126 -0.201422)
			(stroke
				(width 0.1)
				(type default)
			)
			(layer "B.Fab")
		)
		(fp_line
			(start -0.500126 1.598422)
			(end 0.500126 1.598422)
			(stroke
				(width 0.1)
				(type default)
			)
			(layer "B.Fab")
		)
		(pad "1" smd rect
			(at 0 0)
			(size 0.889 0.9906)
			(layers "B.Cu" "B.Mask" "B.Paste")
			(net "PVDDQ_KLM")
		)
		(pad "2" smd rect
			(at 0 1.397)
			(size 0.889 0.9906)
			(layers "B.Cu" "B.Mask" "B.Paste")
			(net "GND")
		)
		(zone
			(layer "B.Cu")
			(hatch none 0.5)
			(connect_pads
				(clearance 0)
			)
			(min_thickness 0.25)
			(keepout
				(tracks allowed)
				(vias not_allowed)
				(pads allowed)
				(copperpour not_allowed)
				(footprints allowed)
			)
			(placement
				(enabled no)
				(sheetname "")
			)
			(fill
				(thermal_gap 0.5)
				(thermal_bridge_width 0.5)
				(island_removal_mode 0)
			)
			(polygon
				(pts
					(xy 81.76768 -126.14275) (xy 81.25968 -126.14275) (xy 81.25968 -125.15215) (xy 81.76768 -125.15215)
				)
			)
		)
		(zone
			(layer "B.Cu")
			(hatch none 0.5)
			(connect_pads
				(clearance 0)
			)
			(min_thickness 0.25)
			(keepout
				(tracks not_allowed)
				(vias allowed)
				(pads allowed)
				(copperpour not_allowed)
				(footprints allowed)
			)
			(placement
				(enabled no)
				(sheetname "")
			)
			(fill
				(thermal_gap 0.5)
				(thermal_bridge_width 0.5)
				(island_removal_mode 0)
			)
			(polygon
				(pts
					(xy 81.76768 -126.14275) (xy 81.25968 -126.14275) (xy 81.25968 -125.15215) (xy 81.76768 -125.15215)
				)
			)
		)
	)
	(footprint ""
		(layer "B.Cu")
		(at 478.730564 -120.39473 -90)
		(property "Reference" "R1W1"
			(at 0 0 90)
			(layer "B.SilkS")
			(hide yes)
			(effects
				(font
					(size 1.27 1.27)
				)
				(justify mirror)
			)
		)
		(property "Value" "*"
			(at -0.064008 -4.108196 270)
			(unlocked yes)
			(layer "B.Fab")
			(hide yes)
			(effects
				(font
					(size 1.27 1.016)
					(thickness 0.1524)
				)
				(justify mirror)
			)
		)
		(property "Device Type" "1MR2F-L-GP_SMD-RG1-1MR2F-L-GP,A"
			(at -0.064008 -5.632196 270)
			(unlocked yes)
			(layer "B.Fab")
			(hide yes)
			(effects
				(font
					(size 1.27 1.016)
					(thickness 0.1524)
				)
				(justify mirror)
			)
		)
		(duplicate_pad_numbers_are_jumpers no)
		(fp_line
			(start -0.508 -0.9398)
			(end 0.508 -0.9398)
			(stroke
				(width 0.1524)
				(type default)
			)
			(layer "B.SilkS")
		)
		(fp_line
			(start 0.508 -0.9398)
			(end 0.508 0.9398)
			(stroke
				(width 0.1524)
				(type default)
			)
			(layer "B.SilkS")
		)
		(fp_rect
			(start 0.508 0.9398)
			(end -0.508 -0.9398)
			(stroke
				(width 0)
				(type default)
			)
			(fill no)
			(layer "B.CrtYd")
		)
		(fp_rect
			(start 0.508 0.9398)
			(end -0.508 -0.9398)
			(stroke
				(width 0)
				(type default)
			)
			(fill no)
			(layer "B.Fab")
		)
		(pad "1" smd custom
			(at 0 -0.4445 90)
			(size 0.1397 0.1397)
			(layers "B.Cu" "B.Mask" "B.Paste")
			(net "P3V3_STBY")
			(options
				(clearance outline)
				(anchor circle)
			)
			(primitives
				(gr_poly
					(pts
						(arc
							(start -0.1778 0.2794)
							(mid -0.249642 0.249642)
							(end -0.2794 0.1778)
						)
						(arc
							(start -0.2794 -0.1778)
							(mid -0.249642 -0.249642)
							(end -0.1778 -0.2794)
						)
						(arc
							(start 0.1778 -0.2794)
							(mid 0.249642 -0.249642)
							(end 0.2794 -0.1778)
						)
						(arc
							(start 0.2794 0.1778)
							(mid 0.249642 0.249642)
							(end 0.1778 0.2794)
						)
					)
					(width 0)
					(fill yes)
				)
			)
		)
		(pad "2" smd custom
			(at 0 0.4445 90)
			(size 0.1397 0.1397)
			(layers "B.Cu" "B.Mask" "B.Paste")
			(net "FM_OCP_MEZZA_PRES_N")
			(options
				(clearance outline)
				(anchor circle)
			)
			(primitives
				(gr_poly
					(pts
						(arc
							(start -0.1778 0.2794)
							(mid -0.249642 0.249642)
							(end -0.2794 0.1778)
						)
						(arc
							(start -0.2794 -0.1778)
							(mid -0.249642 -0.249642)
							(end -0.1778 -0.2794)
						)
						(arc
							(start 0.1778 -0.2794)
							(mid 0.249642 -0.249642)
							(end 0.2794 -0.1778)
						)
						(arc
							(start 0.2794 0.1778)
							(mid 0.249642 0.249642)
							(end 0.1778 0.2794)
						)
					)
					(width 0)
					(fill yes)
				)
			)
		)
	)
	(footprint ""
		(layer "B.Cu")
		(at 371.875558 -41.506648 -90)
		(property "Reference" "R2T16"
			(at 0 0 90)
			(layer "B.SilkS")
			(hide yes)
			(effects
				(font
					(size 1.27 1.27)
				)
				(justify mirror)
			)
		)
		(property "Value" ""
			(at 0 0 90)
			(layer "B.Fab")
			(effects
				(font
					(size 1.27 1.27)
				)
				(justify mirror)
			)
		)
		(duplicate_pad_numbers_are_jumpers no)
		(fp_poly
			(pts
				(xy 0.2794 -0.1016) (xy -0.2794 -0.1016) (xy -0.2794 0.9906) (xy 0.2794 0.9906)
			)
			(stroke
				(width 0)
				(type default)
			)
			(fill no)
			(layer "B.CrtYd")
		)
		(fp_line
			(start -0.2794 0.9906)
			(end -0.2794 -0.1016)
			(stroke
				(width 0.1)
				(type default)
			)
			(layer "B.Fab")
		)
		(fp_line
			(start 0.2794 0.9906)
			(end -0.2794 0.9906)
			(stroke
				(width 0.1)
				(type default)
			)
			(layer "B.Fab")
		)
		(fp_line
			(start -0.2794 -0.1016)
			(end 0.2794 -0.1016)
			(stroke
				(width 0.1)
				(type default)
			)
			(layer "B.Fab")
		)
		(fp_line
			(start 0.2794 -0.1016)
			(end 0.2794 0.9906)
			(stroke
				(width 0.1)
				(type default)
			)
			(layer "B.Fab")
		)
		(pad "1" smd rect
			(at 0 0 90)
			(size 0.508 0.508)
			(layers "B.Cu" "B.Mask" "B.Paste")
			(net "H_CPU_ERR0_GTL_R_N")
		)
		(pad "2" smd rect
			(at 0 0.889 90)
			(size 0.508 0.508)
			(layers "B.Cu" "B.Mask" "B.Paste")
			(net "H_CPU_ERR0_GTL_N")
		)
		(zone
			(layer "B.Cu")
			(hatch none 0.5)
			(connect_pads
				(clearance 0)
			)
			(min_thickness 0.25)
			(keepout
				(tracks not_allowed)
				(vias allowed)
				(pads allowed)
				(copperpour not_allowed)
				(footprints allowed)
			)
			(placement
				(enabled no)
				(sheetname "")
			)
			(fill
				(thermal_gap 0.5)
				(thermal_bridge_width 0.5)
				(island_removal_mode 0)
			)
			(polygon
				(pts
					(xy 371.240558 -41.252648) (xy 371.240558 -41.760648) (xy 371.621558 -41.760648) (xy 371.621558 -41.252648)
				)
			)
		)
		(zone
			(layer "B.Cu")
			(hatch none 0.5)
			(connect_pads
				(clearance 0)
			)
			(min_thickness 0.25)
			(keepout
				(tracks allowed)
				(vias not_allowed)
				(pads allowed)
				(copperpour not_allowed)
				(footprints allowed)
			)
			(placement
				(enabled no)
				(sheetname "")
			)
			(fill
				(thermal_gap 0.5)
				(thermal_bridge_width 0.5)
				(island_removal_mode 0)
			)
			(polygon
				(pts
					(xy 371.621558 -41.252648) (xy 371.621558 -41.760648) (xy 371.240558 -41.760648) (xy 371.240558 -41.252648)
				)
			)
		)
	)
	(footprint ""
		(layer "B.Cu")
		(at 272.931128 -156.960824 90)
		(property "Reference" "C5L2"
			(at 0 0 90)
			(layer "B.SilkS")
			(hide yes)
			(effects
				(font
					(size 1.27 1.27)
				)
				(justify mirror)
			)
		)
		(property "Value" ""
			(at 0 0 90)
			(layer "B.Fab")
			(effects
				(font
					(size 1.27 1.27)
				)
				(justify mirror)
			)
		)
		(duplicate_pad_numbers_are_jumpers no)
		(fp_rect
			(start 0.7239 1.9939)
			(end -0.7239 -0.2159)
			(stroke
				(width 0)
				(type default)
			)
			(fill no)
			(layer "B.CrtYd")
		)
		(fp_line
			(start 0.7239 -0.2159)
			(end 0.7239 1.9939)
			(stroke
				(width 0.1)
				(type default)
			)
			(layer "B.Fab")
		)
		(fp_line
			(start -0.7239 -0.2159)
			(end 0.7239 -0.2159)
			(stroke
				(width 0.1)
				(type default)
			)
			(layer "B.Fab")
		)
		(fp_line
			(start 0.7239 1.9939)
			(end -0.7239 1.9939)
			(stroke
				(width 0.1)
				(type default)
			)
			(layer "B.Fab")
		)
		(fp_line
			(start -0.7239 1.9939)
			(end -0.7239 -0.2159)
			(stroke
				(width 0.1)
				(type default)
			)
			(layer "B.Fab")
		)
		(pad "1" smd rect
			(at 0 0 270)
			(size 1.27 1.016)
			(layers "B.Cu" "B.Mask" "B.Paste")
			(net "PVDDQ_DEF")
		)
		(pad "2" smd rect
			(at 0 1.778 270)
			(size 1.27 1.016)
			(layers "B.Cu" "B.Mask" "B.Paste")
			(net "GND")
		)
		(zone
			(layer "B.Cu")
			(hatch none 0.5)
			(connect_pads
				(clearance 0)
			)
			(min_thickness 0.25)
			(keepout
				(tracks not_allowed)
				(vias allowed)
				(pads allowed)
				(copperpour not_allowed)
				(footprints allowed)
			)
			(placement
				(enabled no)
				(sheetname "")
			)
			(fill
				(thermal_gap 0.5)
				(thermal_bridge_width 0.5)
				(island_removal_mode 0)
			)
			(polygon
				(pts
					(xy 274.201128 -157.595824) (xy 273.439128 -157.595824) (xy 273.439128 -156.325824) (xy 274.201128 -156.325824)
				)
			)
		)
	)
	(footprint ""
		(layer "B.Cu")
		(at 23.114 -81.534)
		(property "Reference" "R9P33"
			(at 0 0 0)
			(layer "B.SilkS")
			(hide yes)
			(effects
				(font
					(size 1.27 1.27)
				)
				(justify mirror)
			)
		)
		(property "Value" ""
			(at 0 0 0)
			(layer "B.Fab")
			(effects
				(font
					(size 1.27 1.27)
				)
				(justify mirror)
			)
		)
		(duplicate_pad_numbers_are_jumpers no)
		(fp_poly
			(pts
				(xy 0.2794 -0.1016) (xy -0.2794 -0.1016) (xy -0.2794 0.9906) (xy 0.2794 0.9906)
			)
			(stroke
				(width 0)
				(type default)
			)
			(fill no)
			(layer "B.CrtYd")
		)
		(fp_line
			(start -0.2794 -0.1016)
			(end 0.2794 -0.1016)
			(stroke
				(width 0.1)
				(type default)
			)
			(layer "B.Fab")
		)
		(fp_line
			(start -0.2794 0.9906)
			(end -0.2794 -0.1016)
			(stroke
				(width 0.1)
				(type default)
			)
			(layer "B.Fab")
		)
		(fp_line
			(start 0.2794 -0.1016)
			(end 0.2794 0.9906)
			(stroke
				(width 0.1)
				(type default)
			)
			(layer "B.Fab")
		)
		(fp_line
			(start 0.2794 0.9906)
			(end -0.2794 0.9906)
			(stroke
				(width 0.1)
				(type default)
			)
			(layer "B.Fab")
		)
		(pad "1" smd rect
			(at 0 0 180)
			(size 0.508 0.508)
			(layers "B.Cu" "B.Mask" "B.Paste")
			(net "P12V_STBY")
		)
		(pad "2" smd rect
			(at 0 0.889 180)
			(size 0.508 0.508)
			(layers "B.Cu" "B.Mask" "B.Paste")
			(net "A_HSC_INAP")
		)
		(zone
			(layer "B.Cu")
			(hatch none 0.5)
			(connect_pads
				(clearance 0)
			)
			(min_thickness 0.25)
			(keepout
				(tracks allowed)
				(vias not_allowed)
				(pads allowed)
				(copperpour not_allowed)
				(footprints allowed)
			)
			(placement
				(enabled no)
				(sheetname "")
			)
			(fill
				(thermal_gap 0.5)
				(thermal_bridge_width 0.5)
				(island_removal_mode 0)
			)
			(polygon
				(pts
					(xy 23.368 -81.28) (xy 22.86 -81.28) (xy 22.86 -80.899) (xy 23.368 -80.899)
				)
			)
		)
		(zone
			(layer "B.Cu")
			(hatch none 0.5)
			(connect_pads
				(clearance 0)
			)
			(min_thickness 0.25)
			(keepout
				(tracks not_allowed)
				(vias allowed)
				(pads allowed)
				(copperpour not_allowed)
				(footprints allowed)
			)
			(placement
				(enabled no)
				(sheetname "")
			)
			(fill
				(thermal_gap 0.5)
				(thermal_bridge_width 0.5)
				(island_removal_mode 0)
			)
			(polygon
				(pts
					(xy 23.368 -80.899) (xy 22.86 -80.899) (xy 22.86 -81.28) (xy 23.368 -81.28)
				)
			)
		)
	)
	(footprint ""
		(layer "B.Cu")
		(at 459.6384 -52.457858)
		(property "Reference" "C1R4"
			(at 0 0 0)
			(layer "B.SilkS")
			(hide yes)
			(effects
				(font
					(size 1.27 1.27)
				)
				(justify mirror)
			)
		)
		(property "Value" ""
			(at 0 0 0)
			(layer "B.Fab")
			(effects
				(font
					(size 1.27 1.27)
				)
				(justify mirror)
			)
		)
		(duplicate_pad_numbers_are_jumpers no)
		(fp_poly
			(pts
				(xy -0.3048 -0.1016) (xy -0.3048 0.9906) (xy 0.3048 0.9906) (xy 0.3048 -0.1016)
			)
			(stroke
				(width 0)
				(type default)
			)
			(fill no)
			(layer "B.CrtYd")
		)
		(fp_line
			(start -0.3048 -0.1016)
			(end 0.3048 -0.1016)
			(stroke
				(width 0.1)
				(type default)
			)
			(layer "B.Fab")
		)
		(fp_line
			(start -0.3048 0.9906)
			(end -0.3048 -0.1016)
			(stroke
				(width 0.1)
				(type default)
			)
			(layer "B.Fab")
		)
		(fp_line
			(start 0.3048 -0.1016)
			(end 0.3048 0.9906)
			(stroke
				(width 0.1)
				(type default)
			)
			(layer "B.Fab")
		)
		(fp_line
			(start 0.3048 0.9906)
			(end -0.3048 0.9906)
			(stroke
				(width 0.1)
				(type default)
			)
			(layer "B.Fab")
		)
		(pad "1" smd rect
			(at 0 0 180)
			(size 0.508 0.508)
			(layers "B.Cu" "B.Mask" "B.Paste")
			(net "P3E_CPU0_PE3_OCP_TXP<1>")
		)
		(pad "2" smd rect
			(at 0 0.889 180)
			(size 0.508 0.508)
			(layers "B.Cu" "B.Mask" "B.Paste")
			(net "P3E_OCP_CPU0_PE3_C_TXP<1>")
		)
		(zone
			(layer "B.Cu")
			(hatch none 0.5)
			(connect_pads
				(clearance 0)
			)
			(min_thickness 0.25)
			(keepout
				(tracks allowed)
				(vias not_allowed)
				(pads allowed)
				(copperpour not_allowed)
				(footprints allowed)
			)
			(placement
				(enabled no)
				(sheetname "")
			)
			(fill
				(thermal_gap 0.5)
				(thermal_bridge_width 0.5)
				(island_removal_mode 0)
			)
			(polygon
				(pts
					(xy 459.8924 -52.203858) (xy 459.3844 -52.203858) (xy 459.3844 -51.822858) (xy 459.8924 -51.822858)
				)
			)
		)
		(zone
			(layer "B.Cu")
			(hatch none 0.5)
			(connect_pads
				(clearance 0)
			)
			(min_thickness 0.25)
			(keepout
				(tracks not_allowed)
				(vias allowed)
				(pads allowed)
				(copperpour not_allowed)
				(footprints allowed)
			)
			(placement
				(enabled no)
				(sheetname "")
			)
			(fill
				(thermal_gap 0.5)
				(thermal_bridge_width 0.5)
				(island_removal_mode 0)
			)
			(polygon
				(pts
					(xy 459.8924 -51.822858) (xy 459.3844 -51.822858) (xy 459.3844 -52.203858) (xy 459.8924 -52.203858)
				)
			)
		)
	)
)
